# S9S_MB_2U (Grand Teton) — schematic netlist excerpt (pin names and nets, part order shuffled) for the footprints in the layout excerpt that follows; sources: Cadence DE-HDL packaged netlist, KiCad conversion of 03242023_DA0F0TMBIJ0_F0T_Motherboard_J_brd_V01_OCP.brd

C1881  Q_CAP  1000PF 50V 5% EMPTY  pkg 0402  page 148 : A = GPU_FPGA_READY_ISO ; B = GND
R1353  Q_RES  100K 1% CHIP  pkg 0402LF  page 154 : A = RMII_BMC_OCP_TX_EN ; B = GND

(kicad_pcb
	(version 20260206)
	(generator "pcbnew")
	(generator_version "10.0")
	(general
		(thickness 1.6)
		(legacy_teardrops no)
	)
	(paper "A4")
	(title_block
		(title "03242023_DA0F0TMBIJ0_F0T_Motherboard_J_brd_V01_OCP.brd")
		(comment 1 "Grand Teton / footprints 1847-1848 of 6105")
	)
	(layers
		(0 "F.Cu" signal "TOP")
		(4 "In1.Cu" signal "GND")
		(6 "In2.Cu" signal "IN1")
		(8 "In3.Cu" signal "GND1")
		(10 "In4.Cu" signal "IN2")
		(12 "In5.Cu" signal "GND2")
		(14 "In6.Cu" signal "IN3")
		(16 "In7.Cu" signal "GND3")
		(18 "In8.Cu" signal "VCC")
		(20 "In9.Cu" signal "VCC1")
		(22 "In10.Cu" signal "GND4")
		(24 "In11.Cu" signal "IN4")
		(26 "In12.Cu" signal "GND5")
		(28 "In13.Cu" signal "IN5")
		(30 "In14.Cu" signal "GND6")
		(32 "In15.Cu" signal "IN6")
		(34 "In16.Cu" signal "GND7")
		(2 "B.Cu" signal "BOTTOM")
		(9 "F.Adhes" user "F.Adhesive")
		(11 "B.Adhes" user "B.Adhesive")
		(13 "F.Paste" user "Package Geometry/Pastemask Top")
		(15 "B.Paste" user "Package Geometry/Pastemask Bottom")
		(5 "F.SilkS" user "Ref Des/Silkscreen Top")
		(7 "B.SilkS" user "Ref Des/Silkscreen Bottom")
		(1 "F.Mask" user "Board Geometry/Soldermask Top")
		(3 "B.Mask" user "Board Geometry/Soldermask Bottom")
		(17 "Dwgs.User" user "User.Drawings")
		(19 "Cmts.User" user "User.Comments")
		(21 "Eco1.User" user "User.Eco1")
		(23 "Eco2.User" user "User.Eco2")
		(25 "Edge.Cuts" user "Board Geometry/Outline")
		(27 "Margin" user)
		(31 "F.CrtYd" user "Package Geometry/Place Bound Top")
		(29 "B.CrtYd" user "Package Geometry/Place Bound Bottom")
		(35 "F.Fab" user "Ref Des/Assembly Top")
		(33 "B.Fab" user "Ref Des/Assembly Bottom")
	)
	(footprint ""
		(layer "F.Cu")
		(at 24.050752 -402.806408 180)
		(property "Reference" "C1881"
			(at 0 0 180)
			(layer "F.SilkS")
			(hide yes)
			(effects
				(font
					(size 1.27 1.27)
				)
			)
		)
		(property "Value" ""
			(at 0 0 180)
			(layer "F.Fab")
			(effects
				(font
					(size 1.27 1.27)
				)
			)
		)
		(duplicate_pad_numbers_are_jumpers no)
		(fp_line
			(start 0.7874 0.4064)
			(end -0.7874 0.4064)
			(stroke
				(width 0.1524)
				(type default)
			)
			(layer "F.SilkS")
		)
		(fp_line
			(start 0.7874 -0.4064)
			(end 0.7874 0.4064)
			(stroke
				(width 0.1524)
				(type default)
			)
			(layer "F.SilkS")
		)
		(fp_line
			(start -0.7874 0.4064)
			(end -0.7874 -0.4064)
			(stroke
				(width 0.1524)
				(type default)
			)
			(layer "F.SilkS")
		)
		(fp_line
			(start -0.7874 -0.4064)
			(end 0.7874 -0.4064)
			(stroke
				(width 0.1524)
				(type default)
			)
			(layer "F.SilkS")
		)
		(fp_line
			(start 0.67945 0.3048)
			(end 0.120396 0.3048)
			(stroke
				(width 0.1)
				(type default)
			)
			(layer "F.Fab")
		)
		(fp_line
			(start 0.67945 -0.3048)
			(end 0.67945 0.3048)
			(stroke
				(width 0.1)
				(type default)
			)
			(layer "F.Fab")
		)
		(fp_line
			(start 0.12065 -0.2794)
			(end 0.12065 -0.3048)
			(stroke
				(width 0.1)
				(type default)
			)
			(layer "F.Fab")
		)
		(fp_line
			(start 0.12065 -0.3048)
			(end 0.67945 -0.3048)
			(stroke
				(width 0.1)
				(type default)
			)
			(layer "F.Fab")
		)
		(fp_line
			(start 0.120396 0.3048)
			(end 0.120396 0.2794)
			(stroke
				(width 0.1)
				(type default)
			)
			(layer "F.Fab")
		)
		(fp_line
			(start 0.120396 0.2794)
			(end -0.12065 0.2794)
			(stroke
				(width 0.1)
				(type default)
			)
			(layer "F.Fab")
		)
		(fp_line
			(start -0.12065 0.3048)
			(end -0.67945 0.3048)
			(stroke
				(width 0.1)
				(type default)
			)
			(layer "F.Fab")
		)
		(fp_line
			(start -0.12065 0.2794)
			(end -0.12065 0.3048)
			(stroke
				(width 0.1)
				(type default)
			)
			(layer "F.Fab")
		)
		(fp_line
			(start -0.12065 -0.2794)
			(end 0.12065 -0.2794)
			(stroke
				(width 0.1)
				(type default)
			)
			(layer "F.Fab")
		)
		(fp_line
			(start -0.12065 -0.305054)
			(end -0.12065 -0.2794)
			(stroke
				(width 0.1)
				(type default)
			)
			(layer "F.Fab")
		)
		(fp_line
			(start -0.67945 0.3048)
			(end -0.67945 -0.305054)
			(stroke
				(width 0.1)
				(type default)
			)
			(layer "F.Fab")
		)
		(fp_line
			(start -0.67945 -0.305054)
			(end -0.12065 -0.305054)
			(stroke
				(width 0.1)
				(type default)
			)
			(layer "F.Fab")
		)
		(pad "1" smd circle
			(at -0.40005 0 180)
			(size 0 0)
			(layers "F.Cu" "F.Mask" "F.Paste")
			(net "GPU_FPGA_READY_ISO")
		)
		(pad "2" smd circle
			(at 0.40005 0 180)
			(size 0 0)
			(layers "F.Cu" "F.Mask" "F.Paste")
			(net "GND")
		)
	)
	(footprint ""
		(layer "F.Cu")
		(at 214.75827 -75.254358 90)
		(property "Reference" "R1353"
			(at 0 0 90)
			(layer "F.SilkS")
			(hide yes)
			(effects
				(font
					(size 1.27 1.27)
				)
			)
		)
		(property "Value" ""
			(at 0 0 90)
			(layer "F.Fab")
			(effects
				(font
					(size 1.27 1.27)
				)
			)
		)
		(duplicate_pad_numbers_are_jumpers no)
		(fp_line
			(start 0.7874 -0.4064)
			(end 0.7874 0.4064)
			(stroke
				(width 0.1524)
				(type default)
			)
			(layer "F.SilkS")
		)
		(fp_line
			(start -0.7874 -0.4064)
			(end 0.7874 -0.4064)
			(stroke
				(width 0.1524)
				(type default)
			)
			(layer "F.SilkS")
		)
		(fp_line
			(start 0.7874 0.4064)
			(end -0.7874 0.4064)
			(stroke
				(width 0.1524)
				(type default)
			)
			(layer "F.SilkS")
		)
		(fp_line
			(start -0.7874 0.4064)
			(end -0.7874 -0.4064)
			(stroke
				(width 0.1524)
				(type default)
			)
			(layer "F.SilkS")
		)
		(fp_line
			(start -0.12065 -0.305054)
			(end -0.12065 -0.2794)
			(stroke
				(width 0.1)
				(type default)
			)
			(layer "F.Fab")
		)
		(fp_line
			(start -0.67945 -0.305054)
			(end -0.12065 -0.305054)
			(stroke
				(width 0.1)
				(type default)
			)
			(layer "F.Fab")
		)
		(fp_line
			(start 0.67945 -0.3048)
			(end 0.67945 0.3048)
			(stroke
				(width 0.1)
				(type default)
			)
			(layer "F.Fab")
		)
		(fp_line
			(start 0.12065 -0.3048)
			(end 0.67945 -0.3048)
			(stroke
				(width 0.1)
				(type default)
			)
			(layer "F.Fab")
		)
		(fp_line
			(start 0.12065 -0.2794)
			(end 0.12065 -0.3048)
			(stroke
				(width 0.1)
				(type default)
			)
			(layer "F.Fab")
		)
		(fp_line
			(start -0.12065 -0.2794)
			(end 0.12065 -0.2794)
			(stroke
				(width 0.1)
				(type default)
			)
			(layer "F.Fab")
		)
		(fp_line
			(start 0.120396 0.2794)
			(end -0.12065 0.2794)
			(stroke
				(width 0.1)
				(type default)
			)
			(layer "F.Fab")
		)
		(fp_line
			(start -0.12065 0.2794)
			(end -0.12065 0.3048)
			(stroke
				(width 0.1)
				(type default)
			)
			(layer "F.Fab")
		)
		(fp_line
			(start 0.67945 0.3048)
			(end 0.120396 0.3048)
			(stroke
				(width 0.1)
				(type default)
			)
			(layer "F.Fab")
		)
		(fp_line
			(start 0.120396 0.3048)
			(end 0.120396 0.2794)
			(stroke
				(width 0.1)
				(type default)
			)
			(layer "F.Fab")
		)
		(fp_line
			(start -0.12065 0.3048)
			(end -0.67945 0.3048)
			(stroke
				(width 0.1)
				(type default)
			)
			(layer "F.Fab")
		)
		(fp_line
			(start -0.67945 0.3048)
			(end -0.67945 -0.305054)
			(stroke
				(width 0.1)
				(type default)
			)
			(layer "F.Fab")
		)
		(pad "1" smd circle
			(at -0.40005 0 90)
			(size 0 0)
			(layers "F.Cu" "F.Mask" "F.Paste")
			(net "RMII_BMC_OCP_TX_EN")
		)
		(pad "2" smd circle
			(at 0.40005 0 90)
			(size 0 0)
			(layers "F.Cu" "F.Mask" "F.Paste")
			(net "GND")
		)
	)
)
